(kicad_pcb
	(version 20260206)
	(generator "pcbnew")
	(generator_version "10.0")
	(general
		(thickness 1.6)
		(legacy_teardrops no)
	)
	(paper "A4")
	(title_block
		(title "Wiwynn_Tioga_Pass_MB.brd")
		(comment 1 "Tioga Pass / footprints 2295-2301 of 4770")
	)
	(layers
		(0 "F.Cu" signal "TOP")
		(4 "In1.Cu" signal "L2GND")
		(6 "In2.Cu" signal "L3")
		(8 "In3.Cu" signal "L4GND")
		(10 "In4.Cu" signal "L5")
		(12 "In5.Cu" signal "L6GND")
		(14 "In6.Cu" signal "L7VCC")
		(16 "In7.Cu" signal "L8VCC")
		(18 "In8.Cu" signal "L9GND")
		(20 "In9.Cu" signal "L10")
		(22 "In10.Cu" signal "L11GND")
		(24 "In11.Cu" signal "L12")
		(26 "In12.Cu" signal "L13GND")
		(2 "B.Cu" signal "BOTTOM")
		(9 "F.Adhes" user "F.Adhesive")
		(11 "B.Adhes" user "B.Adhesive")
		(13 "F.Paste" user "Package Geometry/Pastemask Top")
		(15 "B.Paste" user "Package Geometry/Pastemask Bottom")
		(5 "F.SilkS" user "Ref Des/Silkscreen Top")
		(7 "B.SilkS" user "Ref Des/Silkscreen Bottom")
		(1 "F.Mask" user "Board Geometry/Soldermask Top")
		(3 "B.Mask" user "Board Geometry/Soldermask Bottom")
		(17 "Dwgs.User" user "User.Drawings")
		(19 "Cmts.User" user "User.Comments")
		(21 "Eco1.User" user "User.Eco1")
		(23 "Eco2.User" user "User.Eco2")
		(25 "Edge.Cuts" user "Board Geometry/Outline")
		(27 "Margin" user)
		(31 "F.CrtYd" user "Package Geometry/Place Bound Top")
		(29 "B.CrtYd" user "Package Geometry/Place Bound Bottom")
		(35 "F.Fab" user "Ref Des/Assembly Top")
		(33 "B.Fab" user "Ref Des/Assembly Bottom")
	)
	(footprint ""
		(layer "F.Cu")
		(at 323.723 -35.814 90)
		(property "Reference" "R6F1"
			(at 0 0 90)
			(layer "F.SilkS")
			(hide yes)
			(effects
				(font
					(size 1.27 1.27)
				)
			)
		)
		(property "Value" ""
			(at 0 0 90)
			(layer "F.Fab")
			(effects
				(font
					(size 1.27 1.27)
				)
			)
		)
		(duplicate_pad_numbers_are_jumpers no)
		(fp_poly
			(pts
				(xy -0.2794 -0.1016) (xy 0.2794 -0.1016) (xy 0.2794 0.9906) (xy -0.2794 0.9906)
			)
			(stroke
				(width 0)
				(type default)
			)
			(fill no)
			(layer "F.CrtYd")
		)
		(fp_line
			(start 0.2794 -0.1016)
			(end -0.2794 -0.1016)
			(stroke
				(width 0.1)
				(type default)
			)
			(layer "F.Fab")
		)
		(fp_line
			(start -0.2794 -0.1016)
			(end -0.2794 0.9906)
			(stroke
				(width 0.1)
				(type default)
			)
			(layer "F.Fab")
		)
		(fp_line
			(start 0.2794 0.9906)
			(end 0.2794 -0.1016)
			(stroke
				(width 0.1)
				(type default)
			)
			(layer "F.Fab")
		)
		(fp_line
			(start -0.2794 0.9906)
			(end 0.2794 0.9906)
			(stroke
				(width 0.1)
				(type default)
			)
			(layer "F.Fab")
		)
		(pad "1" smd rect
			(at 0 0 90)
			(size 0.508 0.508)
			(layers "F.Cu" "F.Mask" "F.Paste")
			(net "IRQ_DIMM_SAVE_N")
		)
		(pad "2" smd rect
			(at 0 0.889 90)
			(size 0.508 0.508)
			(layers "F.Cu" "F.Mask" "F.Paste")
			(net "FM_ADR_COMPLETE_DEF_N")
		)
		(zone
			(layer "F.Cu")
			(hatch none 0.5)
			(connect_pads
				(clearance 0)
			)
			(min_thickness 0.25)
			(keepout
				(tracks allowed)
				(vias not_allowed)
				(pads allowed)
				(copperpour not_allowed)
				(footprints allowed)
			)
			(placement
				(enabled no)
				(sheetname "")
			)
			(fill
				(thermal_gap 0.5)
				(thermal_bridge_width 0.5)
				(island_removal_mode 0)
			)
			(polygon
				(pts
					(xy 323.977 -35.56) (xy 323.977 -36.068) (xy 324.358 -36.068) (xy 324.358 -35.56)
				)
			)
		)
		(zone
			(layer "F.Cu")
			(hatch none 0.5)
			(connect_pads
				(clearance 0)
			)
			(min_thickness 0.25)
			(keepout
				(tracks not_allowed)
				(vias allowed)
				(pads allowed)
				(copperpour not_allowed)
				(footprints allowed)
			)
			(placement
				(enabled no)
				(sheetname "")
			)
			(fill
				(thermal_gap 0.5)
				(thermal_bridge_width 0.5)
				(island_removal_mode 0)
			)
			(polygon
				(pts
					(xy 324.358 -35.56) (xy 324.358 -36.068) (xy 323.977 -36.068) (xy 323.977 -35.56)
				)
			)
		)
	)
	(footprint ""
		(layer "F.Cu")
		(at 469.077802 -38.188392 90)
		(property "Reference" "EU9F2"
			(at -0.6096 -1.21793 90)
			(unlocked yes)
			(layer "F.SilkS")
			(effects
				(font
					(size 0.7874 0.5842)
					(thickness 0.1524)
				)
				(justify left)
			)
		)
		(property "Value" ""
			(at 0 0 90)
			(layer "F.Fab")
			(effects
				(font
					(size 1.27 1.27)
				)
			)
		)
		(duplicate_pad_numbers_are_jumpers no)
		(fp_circle
			(center -0.570484 -0.440944)
			(end -0.570484 -0.314198)
			(stroke
				(width 0.254)
				(type default)
			)
			(fill no)
			(layer "F.SilkS")
		)
		(fp_poly
			(pts
				(xy -0.064516 -1.0922) (xy -0.064516 -0.3302) (xy 0.697484 -1.0922)
			)
			(stroke
				(width 0)
				(type default)
			)
			(fill yes)
			(layer "F.SilkS")
		)
		(fp_rect
			(start 0.597408 2.295398)
			(end 2.273808 -0.295402)
			(stroke
				(width 0)
				(type default)
			)
			(fill yes)
			(layer "F.Paste")
		)
		(fp_rect
			(start -0.064516 2.500122)
			(end 2.935478 -0.500126)
			(stroke
				(width 0)
				(type default)
			)
			(fill no)
			(layer "F.CrtYd")
		)
		(fp_line
			(start 2.935478 -0.500126)
			(end 2.935478 2.500122)
			(stroke
				(width 0.1)
				(type default)
			)
			(layer "F.Fab")
		)
		(fp_line
			(start -0.064516 -0.500126)
			(end 2.935478 -0.500126)
			(stroke
				(width 0.1)
				(type default)
			)
			(layer "F.Fab")
		)
		(fp_line
			(start 2.935478 2.500122)
			(end -0.064516 2.500122)
			(stroke
				(width 0.1)
				(type default)
			)
			(layer "F.Fab")
		)
		(fp_line
			(start -0.064516 2.500122)
			(end -0.064516 -0.500126)
			(stroke
				(width 0.1)
				(type default)
			)
			(layer "F.Fab")
		)
		(fp_circle
			(center -0.835152 -0.417322)
			(end -0.835152 -0.290576)
			(stroke
				(width 0.254)
				(type default)
			)
			(fill no)
			(layer "F.Fab")
		)
		(pad "1" smd rect
			(at 0 0 90)
			(size 0.6858 0.3048)
			(layers "F.Cu" "F.Mask" "F.Paste")
			(net "P1V2_AUX_BMC")
		)
		(pad "2" smd rect
			(at 0 0.500126 90)
			(size 0.6858 0.3048)
			(layers "F.Cu" "F.Mask" "F.Paste")
			(net "P1V2_AUX_BMC")
		)
		(pad "3" smd rect
			(at 0 0.999998 90)
			(size 0.6858 0.3048)
			(layers "F.Cu" "F.Mask" "F.Paste")
			(net "P1V2_AUX_BMC")
		)
		(pad "4" smd rect
			(at 0 1.500124 90)
			(size 0.6858 0.3048)
			(layers "F.Cu" "F.Mask" "F.Paste")
			(net "VR_P1V2_BMC_STBY_FB")
		)
		(pad "5" smd rect
			(at 0 1.999996 90)
			(size 0.6858 0.3048)
			(layers "F.Cu" "F.Mask" "F.Paste")
			(net "PWRGD_P1V2_BMC_STBY_R")
		)
		(pad "6" smd rect
			(at 2.871216 1.999996 90)
			(size 0.6858 0.3048)
			(layers "F.Cu" "F.Mask" "F.Paste")
			(net "PWRGD_P2V5_BMC_STBY")
		)
		(pad "7" smd rect
			(at 2.871216 1.500124 90)
			(size 0.6858 0.3048)
			(layers "F.Cu" "F.Mask" "F.Paste")
			(net "P3V3_STBY")
		)
		(pad "8" smd rect
			(at 2.871216 0.999998 90)
			(size 0.6858 0.3048)
			(layers "F.Cu" "F.Mask" "F.Paste")
			(net "P3V3_STBY")
		)
		(pad "9" smd rect
			(at 2.871216 0.500126 90)
			(size 0.6858 0.3048)
			(layers "F.Cu" "F.Mask" "F.Paste")
			(net "P3V3_STBY")
		)
		(pad "10" smd rect
			(at 2.871216 0 90)
			(size 0.6858 0.3048)
			(layers "F.Cu" "F.Mask" "F.Paste")
			(net "P3V3_STBY")
		)
		(pad "11" smd rect
			(at 1.435608 0.999998 90)
			(size 1.6764 2.5908)
			(layers "F.Cu" "F.Mask" "F.Paste")
			(net "GND")
		)
	)
	(footprint ""
		(layer "F.Cu")
		(at 464.7057 -23.0759 90)
		(property "Reference" "R8F2"
			(at 0 0 90)
			(layer "F.SilkS")
			(hide yes)
			(effects
				(font
					(size 1.27 1.27)
				)
			)
		)
		(property "Value" ""
			(at 0 0 90)
			(layer "F.Fab")
			(effects
				(font
					(size 1.27 1.27)
				)
			)
		)
		(duplicate_pad_numbers_are_jumpers no)
		(fp_poly
			(pts
				(xy -0.2794 -0.1016) (xy 0.2794 -0.1016) (xy 0.2794 0.9906) (xy -0.2794 0.9906)
			)
			(stroke
				(width 0)
				(type default)
			)
			(fill no)
			(layer "F.CrtYd")
		)
		(fp_line
			(start 0.2794 -0.1016)
			(end -0.2794 -0.1016)
			(stroke
				(width 0.1)
				(type default)
			)
			(layer "F.Fab")
		)
		(fp_line
			(start -0.2794 -0.1016)
			(end -0.2794 0.9906)
			(stroke
				(width 0.1)
				(type default)
			)
			(layer "F.Fab")
		)
		(fp_line
			(start 0.2794 0.9906)
			(end 0.2794 -0.1016)
			(stroke
				(width 0.1)
				(type default)
			)
			(layer "F.Fab")
		)
		(fp_line
			(start -0.2794 0.9906)
			(end 0.2794 0.9906)
			(stroke
				(width 0.1)
				(type default)
			)
			(layer "F.Fab")
		)
		(pad "1" smd rect
			(at 0 0 90)
			(size 0.508 0.508)
			(layers "F.Cu" "F.Mask" "F.Paste")
			(net "PWRGD_P5V_STBY")
		)
		(pad "2" smd rect
			(at 0 0.889 90)
			(size 0.508 0.508)
			(layers "F.Cu" "F.Mask" "F.Paste")
			(net "VR_P3V3_STBY_EN")
		)
		(zone
			(layer "F.Cu")
			(hatch none 0.5)
			(connect_pads
				(clearance 0)
			)
			(min_thickness 0.25)
			(keepout
				(tracks allowed)
				(vias not_allowed)
				(pads allowed)
				(copperpour not_allowed)
				(footprints allowed)
			)
			(placement
				(enabled no)
				(sheetname "")
			)
			(fill
				(thermal_gap 0.5)
				(thermal_bridge_width 0.5)
				(island_removal_mode 0)
			)
			(polygon
				(pts
					(xy 464.9597 -22.8219) (xy 464.9597 -23.3299) (xy 465.3407 -23.3299) (xy 465.3407 -22.8219)
				)
			)
		)
		(zone
			(layer "F.Cu")
			(hatch none 0.5)
			(connect_pads
				(clearance 0)
			)
			(min_thickness 0.25)
			(keepout
				(tracks not_allowed)
				(vias allowed)
				(pads allowed)
				(copperpour not_allowed)
				(footprints allowed)
			)
			(placement
				(enabled no)
				(sheetname "")
			)
			(fill
				(thermal_gap 0.5)
				(thermal_bridge_width 0.5)
				(island_removal_mode 0)
			)
			(polygon
				(pts
					(xy 465.3407 -22.8219) (xy 465.3407 -23.3299) (xy 464.9597 -23.3299) (xy 464.9597 -22.8219)
				)
			)
		)
	)
	(footprint ""
		(layer "F.Cu")
		(at 405.8285 -105.664 90)
		(property "Reference" "R8C21"
			(at 0 0 90)
			(layer "F.SilkS")
			(hide yes)
			(effects
				(font
					(size 1.27 1.27)
				)
			)
		)
		(property "Value" ""
			(at 0 0 90)
			(layer "F.Fab")
			(effects
				(font
					(size 1.27 1.27)
				)
			)
		)
		(duplicate_pad_numbers_are_jumpers no)
		(fp_poly
			(pts
				(xy -0.2794 -0.1016) (xy 0.2794 -0.1016) (xy 0.2794 0.9906) (xy -0.2794 0.9906)
			)
			(stroke
				(width 0)
				(type default)
			)
			(fill no)
			(layer "F.CrtYd")
		)
		(fp_line
			(start 0.2794 -0.1016)
			(end -0.2794 -0.1016)
			(stroke
				(width 0.1)
				(type default)
			)
			(layer "F.Fab")
		)
		(fp_line
			(start -0.2794 -0.1016)
			(end -0.2794 0.9906)
			(stroke
				(width 0.1)
				(type default)
			)
			(layer "F.Fab")
		)
		(fp_line
			(start 0.2794 0.9906)
			(end 0.2794 -0.1016)
			(stroke
				(width 0.1)
				(type default)
			)
			(layer "F.Fab")
		)
		(fp_line
			(start -0.2794 0.9906)
			(end 0.2794 0.9906)
			(stroke
				(width 0.1)
				(type default)
			)
			(layer "F.Fab")
		)
		(pad "1" smd rect
			(at 0 0 90)
			(size 0.508 0.508)
			(layers "F.Cu" "F.Mask" "F.Paste")
			(net "A_RCOMP_3P3")
		)
		(pad "2" smd rect
			(at 0 0.889 90)
			(size 0.508 0.508)
			(layers "F.Cu" "F.Mask" "F.Paste")
			(net "GND")
		)
		(zone
			(layer "F.Cu")
			(hatch none 0.5)
			(connect_pads
				(clearance 0)
			)
			(min_thickness 0.25)
			(keepout
				(tracks allowed)
				(vias not_allowed)
				(pads allowed)
				(copperpour not_allowed)
				(footprints allowed)
			)
			(placement
				(enabled no)
				(sheetname "")
			)
			(fill
				(thermal_gap 0.5)
				(thermal_bridge_width 0.5)
				(island_removal_mode 0)
			)
			(polygon
				(pts
					(xy 406.0825 -105.41) (xy 406.0825 -105.918) (xy 406.4635 -105.918) (xy 406.4635 -105.41)
				)
			)
		)
		(zone
			(layer "F.Cu")
			(hatch none 0.5)
			(connect_pads
				(clearance 0)
			)
			(min_thickness 0.25)
			(keepout
				(tracks not_allowed)
				(vias allowed)
				(pads allowed)
				(copperpour not_allowed)
				(footprints allowed)
			)
			(placement
				(enabled no)
				(sheetname "")
			)
			(fill
				(thermal_gap 0.5)
				(thermal_bridge_width 0.5)
				(island_removal_mode 0)
			)
			(polygon
				(pts
					(xy 406.4635 -105.41) (xy 406.4635 -105.918) (xy 406.0825 -105.918) (xy 406.0825 -105.41)
				)
			)
		)
	)
	(footprint ""
		(layer "F.Cu")
		(at 198.178928 -53.221382 90)
		(property "Reference" "C4E5"
			(at 0 0 90)
			(layer "F.SilkS")
			(hide yes)
			(effects
				(font
					(size 1.27 1.27)
				)
			)
		)
		(property "Value" ""
			(at 0 0 90)
			(layer "F.Fab")
			(effects
				(font
					(size 1.27 1.27)
				)
			)
		)
		(duplicate_pad_numbers_are_jumpers no)
		(fp_rect
			(start 0.3048 0.9906)
			(end -0.3048 -0.1016)
			(stroke
				(width 0)
				(type default)
			)
			(fill no)
			(layer "F.CrtYd")
		)
		(fp_line
			(start 0.3048 -0.1016)
			(end -0.3048 -0.1016)
			(stroke
				(width 0.1)
				(type default)
			)
			(layer "F.Fab")
		)
		(fp_line
			(start -0.3048 -0.1016)
			(end -0.3048 0.9906)
			(stroke
				(width 0.1)
				(type default)
			)
			(layer "F.Fab")
		)
		(fp_line
			(start 0.3048 0.9906)
			(end 0.3048 -0.1016)
			(stroke
				(width 0.1)
				(type default)
			)
			(layer "F.Fab")
		)
		(fp_line
			(start -0.3048 0.9906)
			(end 0.3048 0.9906)
			(stroke
				(width 0.1)
				(type default)
			)
			(layer "F.Fab")
		)
		(pad "1" smd rect
			(at 0 0 90)
			(size 0.508 0.508)
			(layers "F.Cu" "F.Mask" "F.Paste")
			(net "P5V_STBY")
		)
		(pad "2" smd rect
			(at 0 0.889 90)
			(size 0.508 0.508)
			(layers "F.Cu" "F.Mask" "F.Paste")
			(net "GND")
		)
		(zone
			(layer "F.Cu")
			(hatch none 0.5)
			(connect_pads
				(clearance 0)
			)
			(min_thickness 0.25)
			(keepout
				(tracks allowed)
				(vias not_allowed)
				(pads allowed)
				(copperpour not_allowed)
				(footprints allowed)
			)
			(placement
				(enabled no)
				(sheetname "")
			)
			(fill
				(thermal_gap 0.5)
				(thermal_bridge_width 0.5)
				(island_removal_mode 0)
			)
			(polygon
				(pts
					(xy 198.813928 -53.475382) (xy 198.432928 -53.475382) (xy 198.432928 -52.967382) (xy 198.813928 -52.967382)
				)
			)
		)
		(zone
			(layer "F.Cu")
			(hatch none 0.5)
			(connect_pads
				(clearance 0)
			)
			(min_thickness 0.25)
			(keepout
				(tracks not_allowed)
				(vias allowed)
				(pads allowed)
				(copperpour not_allowed)
				(footprints allowed)
			)
			(placement
				(enabled no)
				(sheetname "")
			)
			(fill
				(thermal_gap 0.5)
				(thermal_bridge_width 0.5)
				(island_removal_mode 0)
			)
			(polygon
				(pts
					(xy 198.813928 -53.475382) (xy 198.432928 -53.475382) (xy 198.432928 -52.967382) (xy 198.813928 -52.967382)
				)
			)
		)
	)
	(footprint ""
		(layer "F.Cu")
		(at 171.989496 -74.972672 90)
		(property "Reference" "R4W3"
			(at -0.8382 -0.67818 90)
			(unlocked yes)
			(layer "F.SilkS")
			(effects
				(font
					(size 0.4064 0.254)
					(thickness 0.1524)
				)
				(justify left)
			)
		)
		(property "Value" ""
			(at 0 0 90)
			(layer "F.Fab")
			(effects
				(font
					(size 1.27 1.27)
				)
			)
		)
		(duplicate_pad_numbers_are_jumpers no)
		(fp_poly
			(pts
				(xy -0.2794 -0.1016) (xy 0.2794 -0.1016) (xy 0.2794 0.9906) (xy -0.2794 0.9906)
			)
			(stroke
				(width 0)
				(type default)
			)
			(fill no)
			(layer "F.CrtYd")
		)
		(fp_line
			(start 0.2794 -0.1016)
			(end -0.2794 -0.1016)
			(stroke
				(width 0.1)
				(type default)
			)
			(layer "F.Fab")
		)
		(fp_line
			(start -0.2794 -0.1016)
			(end -0.2794 0.9906)
			(stroke
				(width 0.1)
				(type default)
			)
			(layer "F.Fab")
		)
		(fp_line
			(start 0.2794 0.9906)
			(end 0.2794 -0.1016)
			(stroke
				(width 0.1)
				(type default)
			)
			(layer "F.Fab")
		)
		(fp_line
			(start -0.2794 0.9906)
			(end 0.2794 0.9906)
			(stroke
				(width 0.1)
				(type default)
			)
			(layer "F.Fab")
		)
		(pad "1" smd rect
			(at 0 0 90)
			(size 0.508 0.508)
			(layers "F.Cu" "F.Mask" "F.Paste")
			(net "P3V3_DB1200")
		)
		(pad "2" smd rect
			(at 0 0.889 90)
			(size 0.508 0.508)
			(layers "F.Cu" "F.Mask" "F.Paste")
			(net "SMB_HOST_STBY_LVC3_SDA_R2")
		)
		(zone
			(layer "F.Cu")
			(hatch none 0.5)
			(connect_pads
				(clearance 0)
			)
			(min_thickness 0.25)
			(keepout
				(tracks allowed)
				(vias not_allowed)
				(pads allowed)
				(copperpour not_allowed)
				(footprints allowed)
			)
			(placement
				(enabled no)
				(sheetname "")
			)
			(fill
				(thermal_gap 0.5)
				(thermal_bridge_width 0.5)
				(island_removal_mode 0)
			)
			(polygon
				(pts
					(xy 172.243496 -74.718672) (xy 172.243496 -75.226672) (xy 172.624496 -75.226672) (xy 172.624496 -74.718672)
				)
			)
		)
		(zone
			(layer "F.Cu")
			(hatch none 0.5)
			(connect_pads
				(clearance 0)
			)
			(min_thickness 0.25)
			(keepout
				(tracks not_allowed)
				(vias allowed)
				(pads allowed)
				(copperpour not_allowed)
				(footprints allowed)
			)
			(placement
				(enabled no)
				(sheetname "")
			)
			(fill
				(thermal_gap 0.5)
				(thermal_bridge_width 0.5)
				(island_removal_mode 0)
			)
			(polygon
				(pts
					(xy 172.624496 -74.718672) (xy 172.624496 -75.226672) (xy 172.243496 -75.226672) (xy 172.243496 -74.718672)
				)
			)
		)
	)
	(footprint ""
		(layer "F.Cu")
		(at 452.628 -148.59 180)
		(property "Reference" "R25W164"
			(at -0.8382 -0.67818 180)
			(unlocked yes)
			(layer "F.SilkS")
			(effects
				(font
					(size 0.4064 0.254)
					(thickness 0.1524)
				)
				(justify left)
			)
		)
		(property "Value" ""
			(at 0 0 180)
			(layer "F.Fab")
			(effects
				(font
					(size 1.27 1.27)
				)
			)
		)
		(duplicate_pad_numbers_are_jumpers no)
		(fp_poly
			(pts
				(xy -0.2794 -0.1016) (xy 0.2794 -0.1016) (xy 0.2794 0.9906) (xy -0.2794 0.9906)
			)
			(stroke
				(width 0)
				(type default)
			)
			(fill no)
			(layer "F.CrtYd")
		)
		(fp_line
			(start 0.2794 0.9906)
			(end 0.2794 -0.1016)
			(stroke
				(width 0.1)
				(type default)
			)
			(layer "F.Fab")
		)
		(fp_line
			(start 0.2794 -0.1016)
			(end -0.2794 -0.1016)
			(stroke
				(width 0.1)
				(type default)
			)
			(layer "F.Fab")
		)
		(fp_line
			(start -0.2794 0.9906)
			(end 0.2794 0.9906)
			(stroke
				(width 0.1)
				(type default)
			)
			(layer "F.Fab")
		)
		(fp_line
			(start -0.2794 -0.1016)
			(end -0.2794 0.9906)
			(stroke
				(width 0.1)
				(type default)
			)
			(layer "F.Fab")
		)
		(pad "1" smd rect
			(at 0 0 180)
			(size 0.508 0.508)
			(layers "F.Cu" "F.Mask" "F.Paste")
			(net "P1V05_PCH_STBY")
		)
		(pad "2" smd rect
			(at 0 0.889 180)
			(size 0.508 0.508)
			(layers "F.Cu" "F.Mask" "F.Paste")
			(net "P0V7_GTL2014_VREF_6")
		)
		(zone
			(layer "F.Cu")
			(hatch none 0.5)
			(connect_pads
				(clearance 0)
			)
			(min_thickness 0.25)
			(keepout
				(tracks not_allowed)
				(vias allowed)
				(pads allowed)
				(copperpour not_allowed)
				(footprints allowed)
			)
			(placement
				(enabled no)
				(sheetname "")
			)
			(fill
				(thermal_gap 0.5)
				(thermal_bridge_width 0.5)
				(island_removal_mode 0)
			)
			(polygon
				(pts
					(xy 452.882 -149.225) (xy 452.374 -149.225) (xy 452.374 -148.844) (xy 452.882 -148.844)
				)
			)
		)
		(zone
			(layer "F.Cu")
			(hatch none 0.5)
			(connect_pads
				(clearance 0)
			)
			(min_thickness 0.25)
			(keepout
				(tracks allowed)
				(vias not_allowed)
				(pads allowed)
				(copperpour not_allowed)
				(footprints allowed)
			)
			(placement
				(enabled no)
				(sheetname "")
			)
			(fill
				(thermal_gap 0.5)
				(thermal_bridge_width 0.5)
				(island_removal_mode 0)
			)
			(polygon
				(pts
					(xy 452.882 -148.844) (xy 452.374 -148.844) (xy 452.374 -149.225) (xy 452.882 -149.225)
				)
			)
		)
	)
)
